# T6G (Grand Teton) — schematic netlist excerpt (pin names and nets, part order shuffled) for the footprints in the layout excerpt that follows; sources: Cadence DE-HDL packaged netlist, KiCad conversion of 04192023_DAF0TMB3IC0_F0TG_MB_C_brd_V02_OCP.brd

R467  Q_RES  33 5% CHIP  pkg 0402LF  page 29 : A = SPI_CPU0_D3 ; B = SPI_CPU0_R_D3
C6517  Q_CAP_DIFFBUS  DIFF BUS_0.22UF 6.3V 20% X6S  pkg C0201  page 275 : \1\ = P5E_CPU0_P0_TX_BUF_C_DP<8> ; \2\ = P5E_CPU0_P0_TX_BUF_DP<8>
R6050  Q_RES  100K 1% EMPTY  pkg 0402LF  page 188 : A = SW_P3V3_EN ; B = GND

(kicad_pcb
	(version 20260206)
	(generator "pcbnew")
	(generator_version "10.0")
	(general
		(thickness 1.6)
		(legacy_teardrops no)
	)
	(paper "A4")
	(title_block
		(title "04192023_DAF0TMB3IC0_F0TG_MB_C_brd_V02_OCP.brd")
		(comment 1 "Grand Teton / footprints 1540-1542 of 8354")
	)
	(layers
		(0 "F.Cu" signal "TOP")
		(4 "In1.Cu" signal "GND")
		(6 "In2.Cu" signal "IN1")
		(8 "In3.Cu" signal "GND1")
		(10 "In4.Cu" signal "IN2")
		(12 "In5.Cu" signal "GND2")
		(14 "In6.Cu" signal "IN3")
		(16 "In7.Cu" signal "GND3")
		(18 "In8.Cu" signal "VCC")
		(20 "In9.Cu" signal "VCC1")
		(22 "In10.Cu" signal "GND4")
		(24 "In11.Cu" signal "IN4")
		(26 "In12.Cu" signal "GND5")
		(28 "In13.Cu" signal "IN5")
		(30 "In14.Cu" signal "GND6")
		(32 "In15.Cu" signal "IN6")
		(34 "In16.Cu" signal "GND7")
		(2 "B.Cu" signal "BOTTOM")
		(9 "F.Adhes" user "F.Adhesive")
		(11 "B.Adhes" user "B.Adhesive")
		(13 "F.Paste" user "Package Geometry/Pastemask Top")
		(15 "B.Paste" user "Package Geometry/Pastemask Bottom")
		(5 "F.SilkS" user "Ref Des/Silkscreen Top")
		(7 "B.SilkS" user "Ref Des/Silkscreen Bottom")
		(1 "F.Mask" user "Board Geometry/Soldermask Top")
		(3 "B.Mask" user "Board Geometry/Soldermask Bottom")
		(17 "Dwgs.User" user "User.Drawings")
		(19 "Cmts.User" user "User.Comments")
		(21 "Eco1.User" user "User.Eco1")
		(23 "Eco2.User" user "User.Eco2")
		(25 "Edge.Cuts" user "Board Geometry/Outline")
		(27 "Margin" user)
		(31 "F.CrtYd" user "Package Geometry/Place Bound Top")
		(29 "B.CrtYd" user "Package Geometry/Place Bound Bottom")
		(35 "F.Fab" user "Ref Des/Assembly Top")
		(33 "B.Fab" user "Ref Des/Assembly Bottom")
	)
	(footprint ""
		(layer "F.Cu")
		(at 205.232 -128.016)
		(property "Reference" "R6050"
			(at 0 0 0)
			(layer "F.SilkS")
			(hide yes)
			(effects
				(font
					(size 1.27 1.27)
				)
			)
		)
		(property "Value" ""
			(at 0 0 0)
			(layer "F.Fab")
			(effects
				(font
					(size 1.27 1.27)
				)
			)
		)
		(duplicate_pad_numbers_are_jumpers no)
		(fp_line
			(start -0.7874 -0.4064)
			(end 0.7874 -0.4064)
			(stroke
				(width 0.1524)
				(type default)
			)
			(layer "F.SilkS")
		)
		(fp_line
			(start -0.7874 0.4064)
			(end -0.7874 -0.4064)
			(stroke
				(width 0.1524)
				(type default)
			)
			(layer "F.SilkS")
		)
		(fp_line
			(start 0.7874 -0.4064)
			(end 0.7874 0.4064)
			(stroke
				(width 0.1524)
				(type default)
			)
			(layer "F.SilkS")
		)
		(fp_line
			(start 0.7874 0.4064)
			(end -0.7874 0.4064)
			(stroke
				(width 0.1524)
				(type default)
			)
			(layer "F.SilkS")
		)
		(fp_line
			(start -0.67945 -0.305054)
			(end -0.12065 -0.305054)
			(stroke
				(width 0.1)
				(type default)
			)
			(layer "F.Fab")
		)
		(fp_line
			(start -0.67945 0.3048)
			(end -0.67945 -0.305054)
			(stroke
				(width 0.1)
				(type default)
			)
			(layer "F.Fab")
		)
		(fp_line
			(start -0.12065 -0.305054)
			(end -0.12065 -0.2794)
			(stroke
				(width 0.1)
				(type default)
			)
			(layer "F.Fab")
		)
		(fp_line
			(start -0.12065 -0.2794)
			(end 0.12065 -0.2794)
			(stroke
				(width 0.1)
				(type default)
			)
			(layer "F.Fab")
		)
		(fp_line
			(start -0.12065 0.2794)
			(end -0.12065 0.3048)
			(stroke
				(width 0.1)
				(type default)
			)
			(layer "F.Fab")
		)
		(fp_line
			(start -0.12065 0.3048)
			(end -0.67945 0.3048)
			(stroke
				(width 0.1)
				(type default)
			)
			(layer "F.Fab")
		)
		(fp_line
			(start 0.120396 0.2794)
			(end -0.12065 0.2794)
			(stroke
				(width 0.1)
				(type default)
			)
			(layer "F.Fab")
		)
		(fp_line
			(start 0.120396 0.3048)
			(end 0.120396 0.2794)
			(stroke
				(width 0.1)
				(type default)
			)
			(layer "F.Fab")
		)
		(fp_line
			(start 0.12065 -0.3048)
			(end 0.67945 -0.3048)
			(stroke
				(width 0.1)
				(type default)
			)
			(layer "F.Fab")
		)
		(fp_line
			(start 0.12065 -0.2794)
			(end 0.12065 -0.3048)
			(stroke
				(width 0.1)
				(type default)
			)
			(layer "F.Fab")
		)
		(fp_line
			(start 0.67945 -0.3048)
			(end 0.67945 0.3048)
			(stroke
				(width 0.1)
				(type default)
			)
			(layer "F.Fab")
		)
		(fp_line
			(start 0.67945 0.3048)
			(end 0.120396 0.3048)
			(stroke
				(width 0.1)
				(type default)
			)
			(layer "F.Fab")
		)
		(pad "1" smd circle
			(at -0.40005 0)
			(size 0 0)
			(layers "F.Cu" "F.Mask" "F.Paste")
			(net "SW_P3V3_EN")
		)
		(pad "2" smd circle
			(at 0.40005 0)
			(size 0 0)
			(layers "F.Cu" "F.Mask" "F.Paste")
			(net "GND")
		)
	)
	(footprint ""
		(layer "F.Cu")
		(at 402.253958 -328.418952 180)
		(property "Reference" "R467"
			(at 0 0 180)
			(layer "F.SilkS")
			(hide yes)
			(effects
				(font
					(size 1.27 1.27)
				)
			)
		)
		(property "Value" ""
			(at 0 0 180)
			(layer "F.Fab")
			(effects
				(font
					(size 1.27 1.27)
				)
			)
		)
		(duplicate_pad_numbers_are_jumpers no)
		(fp_line
			(start 0.7874 0.4064)
			(end -0.7874 0.4064)
			(stroke
				(width 0.1524)
				(type default)
			)
			(layer "F.SilkS")
		)
		(fp_line
			(start 0.7874 -0.4064)
			(end 0.7874 0.4064)
			(stroke
				(width 0.1524)
				(type default)
			)
			(layer "F.SilkS")
		)
		(fp_line
			(start -0.7874 0.4064)
			(end -0.7874 -0.4064)
			(stroke
				(width 0.1524)
				(type default)
			)
			(layer "F.SilkS")
		)
		(fp_line
			(start -0.7874 -0.4064)
			(end 0.7874 -0.4064)
			(stroke
				(width 0.1524)
				(type default)
			)
			(layer "F.SilkS")
		)
		(fp_line
			(start 0.67945 0.3048)
			(end 0.120396 0.3048)
			(stroke
				(width 0.1)
				(type default)
			)
			(layer "F.Fab")
		)
		(fp_line
			(start 0.67945 -0.3048)
			(end 0.67945 0.3048)
			(stroke
				(width 0.1)
				(type default)
			)
			(layer "F.Fab")
		)
		(fp_line
			(start 0.12065 -0.2794)
			(end 0.12065 -0.3048)
			(stroke
				(width 0.1)
				(type default)
			)
			(layer "F.Fab")
		)
		(fp_line
			(start 0.12065 -0.3048)
			(end 0.67945 -0.3048)
			(stroke
				(width 0.1)
				(type default)
			)
			(layer "F.Fab")
		)
		(fp_line
			(start 0.120396 0.3048)
			(end 0.120396 0.2794)
			(stroke
				(width 0.1)
				(type default)
			)
			(layer "F.Fab")
		)
		(fp_line
			(start 0.120396 0.2794)
			(end -0.12065 0.2794)
			(stroke
				(width 0.1)
				(type default)
			)
			(layer "F.Fab")
		)
		(fp_line
			(start -0.12065 0.3048)
			(end -0.67945 0.3048)
			(stroke
				(width 0.1)
				(type default)
			)
			(layer "F.Fab")
		)
		(fp_line
			(start -0.12065 0.2794)
			(end -0.12065 0.3048)
			(stroke
				(width 0.1)
				(type default)
			)
			(layer "F.Fab")
		)
		(fp_line
			(start -0.12065 -0.2794)
			(end 0.12065 -0.2794)
			(stroke
				(width 0.1)
				(type default)
			)
			(layer "F.Fab")
		)
		(fp_line
			(start -0.12065 -0.305054)
			(end -0.12065 -0.2794)
			(stroke
				(width 0.1)
				(type default)
			)
			(layer "F.Fab")
		)
		(fp_line
			(start -0.67945 0.3048)
			(end -0.67945 -0.305054)
			(stroke
				(width 0.1)
				(type default)
			)
			(layer "F.Fab")
		)
		(fp_line
			(start -0.67945 -0.305054)
			(end -0.12065 -0.305054)
			(stroke
				(width 0.1)
				(type default)
			)
			(layer "F.Fab")
		)
		(pad "1" smd circle
			(at -0.40005 0 180)
			(size 0 0)
			(layers "F.Cu" "F.Mask" "F.Paste")
			(net "SPI_CPU0_D3")
		)
		(pad "2" smd circle
			(at 0.40005 0 180)
			(size 0 0)
			(layers "F.Cu" "F.Mask" "F.Paste")
			(net "SPI_CPU0_R_D3")
		)
	)
	(footprint ""
		(layer "F.Cu")
		(at 329.188826 -416.899344 -90)
		(property "Reference" "C6517"
			(at 0 0 270)
			(layer "F.SilkS")
			(hide yes)
			(effects
				(font
					(size 1.27 1.27)
				)
			)
		)
		(property "Value" ""
			(at 0 0 270)
			(layer "F.Fab")
			(effects
				(font
					(size 1.27 1.27)
				)
			)
		)
		(duplicate_pad_numbers_are_jumpers no)
		(fp_line
			(start -0.299974 0.150114)
			(end -0.299974 -0.150114)
			(stroke
				(width 0.1)
				(type default)
			)
			(layer "F.Fab")
		)
		(fp_line
			(start 0.299974 0.150114)
			(end -0.299974 0.150114)
			(stroke
				(width 0.1)
				(type default)
			)
			(layer "F.Fab")
		)
		(fp_line
			(start -0.299974 -0.150114)
			(end 0.299974 -0.150114)
			(stroke
				(width 0.1)
				(type default)
			)
			(layer "F.Fab")
		)
		(fp_line
			(start 0.299974 -0.150114)
			(end 0.299974 0.150114)
			(stroke
				(width 0.1)
				(type default)
			)
			(layer "F.Fab")
		)
		(pad "1" smd rect
			(at -0.2667 0 270)
			(size 0.3048 0.381)
			(layers "F.Cu" "F.Mask" "F.Paste")
			(net "P5E_CPU0_P0_TX_BUF_C_DP<8>")
		)
		(pad "2" smd rect
			(at 0.2667 0 270)
			(size 0.3048 0.381)
			(layers "F.Cu" "F.Mask" "F.Paste")
			(net "P5E_CPU0_P0_TX_BUF_DP<8>")
		)
	)
)
